(kicad_pcb
	(version 20241229)
	(generator "pcbnew")
	(generator_version "9.0")
	(general
		(thickness 1.61)
		(legacy_teardrops no)
	)
	(paper "A3")
	(title_block
		(title "RDIMM DDR5 Tester")
		(date "2026-05-21")
		(rev "2.2.0")
		(company "Antmicro")
		(comment 9 "footprints 235-237 of 796")
	)
	(layers
		(0 "F.Cu" signal)
		(4 "In1.Cu" power)
		(6 "In2.Cu" mixed)
		(8 "In3.Cu" power)
		(10 "In4.Cu" mixed)
		(12 "In5.Cu" power)
		(14 "In6.Cu" mixed)
		(16 "In7.Cu" power)
		(18 "In8.Cu" power)
		(20 "In9.Cu" mixed)
		(22 "In10.Cu" power)
		(2 "B.Cu" signal)
		(9 "F.Adhes" user "F.Adhesive")
		(11 "B.Adhes" user "B.Adhesive")
		(13 "F.Paste" user)
		(15 "B.Paste" user)
		(5 "F.SilkS" user "F.Silkscreen")
		(7 "B.SilkS" user "B.Silkscreen")
		(1 "F.Mask" user)
		(3 "B.Mask" user)
		(17 "Dwgs.User" user "User.Drawings")
		(19 "Cmts.User" user "User.Comments")
		(21 "Eco1.User" user "User.Eco1")
		(23 "Eco2.User" user "User.Eco2")
		(25 "Edge.Cuts" user)
		(27 "Margin" user)
		(31 "F.CrtYd" user "F.Courtyard")
		(29 "B.CrtYd" user "B.Courtyard")
		(35 "F.Fab" user)
		(33 "B.Fab" user)
	)
	(footprint "antmicro-footprints:C_0402_1005Metric"
		(layer "F.Cu")
		(at 250.4 115.98 90)
		(descr "Capacitor SMD 0402")
		(tags "capacitor SMD 0402")
		(property "Reference" "C6"
			(at -0.61 -0.52 90)
			(layer "F.SilkS")
			(effects
				(font
					(size 0.7 0.7)
					(thickness 0.15)
				)
				(justify left bottom)
			)
		)
		(property "Value" "C_100n_0402"
			(at -1.022927 2.155213 90)
			(layer "F.Fab")
			(effects
				(font
					(size 0.7 0.7)
					(thickness 0.15)
				)
				(justify left bottom)
			)
		)
		(property "Datasheet" "https://www.murata.com/products/productdetail?partno=GRM155R61H104KE14%23"
			(at 0 0 90)
			(layer "F.Fab")
			(hide yes)
			(effects
				(font
					(size 1.27 1.27)
					(thickness 0.15)
				)
			)
		)
		(property "MPN" "GRM155R61H104KE14D"
			(at 0 0 90)
			(unlocked yes)
			(layer "F.Fab")
			(hide yes)
			(effects
				(font
					(size 1 1)
					(thickness 0.15)
				)
			)
		)
		(property "Manufacturer" "Murata"
			(at 0 0 90)
			(unlocked yes)
			(layer "F.Fab")
			(hide yes)
			(effects
				(font
					(size 1 1)
					(thickness 0.15)
				)
			)
		)
		(property "License" "Apache-2.0"
			(at 0 0 90)
			(unlocked yes)
			(layer "F.Fab")
			(hide yes)
			(effects
				(font
					(size 1 1)
					(thickness 0.15)
				)
			)
		)
		(property "Author" "Antmicro"
			(at 0 0 90)
			(unlocked yes)
			(layer "F.Fab")
			(hide yes)
			(effects
				(font
					(size 1 1)
					(thickness 0.15)
				)
			)
		)
		(property "Val" "100n"
			(at 0 0 90)
			(unlocked yes)
			(layer "F.Fab")
			(hide yes)
			(effects
				(font
					(size 1 1)
					(thickness 0.15)
				)
			)
		)
		(property "Voltage" "50V"
			(at 0 0 90)
			(unlocked yes)
			(layer "F.Fab")
			(hide yes)
			(effects
				(font
					(size 1 1)
					(thickness 0.15)
				)
			)
		)
		(property "Dielectric" "X5R"
			(at 0 0 90)
			(unlocked yes)
			(layer "F.Fab")
			(hide yes)
			(effects
				(font
					(size 1 1)
					(thickness 0.15)
				)
			)
		)
		(sheetname "/DDR5 RDIMM/")
		(sheetfile "ddr5-rdimm.kicad_sch")
		(attr smd)
		(fp_rect
			(start -0.925 -0.47)
			(end 0.925 0.47)
			(stroke
				(width 0.05)
				(type default)
			)
			(fill no)
			(layer "F.CrtYd")
		)
		(fp_line
			(start 0.504 -0.25)
			(end 0.504 0.248)
			(stroke
				(width 0.15)
				(type solid)
			)
			(layer "F.Fab")
		)
		(fp_line
			(start -0.494 -0.25)
			(end 0.504 -0.25)
			(stroke
				(width 0.15)
				(type solid)
			)
			(layer "F.Fab")
		)
		(fp_line
			(start 0.504 0.248)
			(end -0.494 0.248)
			(stroke
				(width 0.15)
				(type solid)
			)
			(layer "F.Fab")
		)
		(fp_line
			(start -0.494 0.248)
			(end -0.494 -0.25)
			(stroke
				(width 0.15)
				(type solid)
			)
			(layer "F.Fab")
		)
		(fp_text user "Author: Antmicro"
			(at -0.939 3.399 90)
			(layer "F.Fab")
			(effects
				(font
					(size 0.7 0.7)
					(thickness 0.15)
				)
				(justify left bottom)
			)
		)
		(fp_text user "License: Apache-2.0"
			(at -0.939 5.799 90)
			(layer "F.Fab")
			(effects
				(font
					(size 0.7 0.7)
					(thickness 0.15)
				)
				(justify left bottom)
			)
		)
		(fp_text user "${REFERENCE}"
			(at -0.939 4.599 90)
			(layer "F.Fab")
			(effects
				(font
					(size 0.7 0.7)
					(thickness 0.15)
				)
				(justify left bottom)
			)
		)
		(pad "1" smd roundrect
			(at -0.48 0 90)
			(size 0.59 0.64)
			(layers "F.Cu" "F.Mask" "F.Paste")
			(roundrect_rratio 0.25)
			(net 1 "GND")
			(pintype "passive")
		)
		(pad "2" smd roundrect
			(at 0.48 0 90)
			(size 0.59 0.64)
			(layers "F.Cu" "F.Mask" "F.Paste")
			(roundrect_rratio 0.25)
			(net 802 "/DDR5 RDIMM/VIN_BULK")
			(pintype "passive")
		)
	)
	(footprint "antmicro-footprints:X1QFN-16-1EP_2.5x2.5mm"
		(layer "F.Cu")
		(at 138.423499 180.299)
		(property "Reference" "U9"
			(at 1.651 1.85 0)
			(unlocked yes)
			(layer "F.SilkS")
			(effects
				(font
					(size 0.7 0.7)
					(thickness 0.15)
				)
				(justify left bottom)
			)
		)
		(property "Value" "SN74HC595B"
			(at -6.9 2.69 0)
			(unlocked yes)
			(layer "F.Fab")
			(effects
				(font
					(size 0.7 0.7)
					(thickness 0.15)
				)
				(justify left bottom)
			)
		)
		(property "Datasheet" "https://www.ti.com/general/docs/suppproductinfo.tsp?distId=26&gotoUrl=https://www.ti.com/lit/gpn/sn74hc595b"
			(at 0 0 0)
			(layer "F.Fab")
			(hide yes)
			(effects
				(font
					(size 1.27 1.27)
					(thickness 0.15)
				)
			)
		)
		(property "MPN" "SN74HC595BRWNR"
			(at 0 0 0)
			(unlocked yes)
			(layer "F.Fab")
			(hide yes)
			(effects
				(font
					(size 1 1)
					(thickness 0.15)
				)
			)
		)
		(property "Manufacturer" "Texas Instruments"
			(at 0 0 0)
			(unlocked yes)
			(layer "F.Fab")
			(hide yes)
			(effects
				(font
					(size 1 1)
					(thickness 0.15)
				)
			)
		)
		(property "Author" "Antmicro"
			(at 0 0 0)
			(unlocked yes)
			(layer "F.Fab")
			(hide yes)
			(effects
				(font
					(size 1 1)
					(thickness 0.15)
				)
			)
		)
		(property "License" "Apache-2.0"
			(at 0 0 0)
			(unlocked yes)
			(layer "F.Fab")
			(hide yes)
			(effects
				(font
					(size 1 1)
					(thickness 0.15)
				)
			)
		)
		(sheetname "/Debug FTDI + VNA/")
		(sheetfile "debug-ftdi.kicad_sch")
		(attr smd)
		(fp_line
			(start -1.351 -1.351)
			(end -0.803 -1.351)
			(stroke
				(width 0.15)
				(type solid)
			)
			(layer "F.SilkS")
		)
		(fp_line
			(start -1.351 1.35)
			(end -1.351 0.8)
			(stroke
				(width 0.15)
				(type solid)
			)
			(layer "F.SilkS")
		)
		(fp_line
			(start -0.803 1.35)
			(end -1.351 1.35)
			(stroke
				(width 0.15)
				(type solid)
			)
			(layer "F.SilkS")
		)
		(fp_line
			(start 0.8 -1.351)
			(end 1.35 -1.351)
			(stroke
				(width 0.15)
				(type solid)
			)
			(layer "F.SilkS")
		)
		(fp_line
			(start 1.35 -1.351)
			(end 1.35 -0.803)
			(stroke
				(width 0.15)
				(type solid)
			)
			(layer "F.SilkS")
		)
		(fp_line
			(start 1.35 0.8)
			(end 1.35 1.35)
			(stroke
				(width 0.15)
				(type solid)
			)
			(layer "F.SilkS")
		)
		(fp_line
			(start 1.35 1.35)
			(end 0.8 1.35)
			(stroke
				(width 0.15)
				(type solid)
			)
			(layer "F.SilkS")
		)
		(fp_circle
			(center -1.752 -0.6)
			(end -1.702 -0.6)
			(stroke
				(width 0.15)
				(type solid)
			)
			(fill yes)
			(layer "F.SilkS")
		)
		(fp_rect
			(start -1.75 -1.75)
			(end 1.749 1.749)
			(stroke
				(width 0.05)
				(type solid)
			)
			(fill no)
			(layer "F.CrtYd")
		)
		(fp_line
			(start -1.25 -1.05)
			(end -1.05 -1.25)
			(stroke
				(width 0.15)
				(type solid)
			)
			(layer "F.Fab")
		)
		(fp_rect
			(start -1.25 -1.25)
			(end 1.249 1.249)
			(stroke
				(width 0.15)
				(type solid)
			)
			(fill no)
			(layer "F.Fab")
		)
		(fp_text user "${REFERENCE}"
			(at -6.9 5.89 0)
			(layer "F.Fab")
			(effects
				(font
					(size 0.7 0.7)
					(thickness 0.15)
				)
				(justify left bottom)
			)
		)
		(fp_text user "Author: Antmicro"
			(at -6.9 4.69 0)
			(layer "F.Fab")
			(effects
				(font
					(size 0.7 0.7)
					(thickness 0.15)
				)
				(justify left bottom)
			)
		)
		(fp_text user "License: Apache-2.0"
			(at -6.9 7.09 0)
			(layer "F.Fab")
			(effects
				(font
					(size 0.7 0.7)
					(thickness 0.15)
				)
				(justify left bottom)
			)
		)
		(pad "1" smd roundrect
			(at -1.151 -0.6)
			(size 0.6 0.2)
			(layers "F.Cu" "F.Mask" "F.Paste")
			(roundrect_rratio 0.25)
			(net 416 "unconnected-(U9-QB-Pad1)")
			(pinfunction "QB")
			(pintype "output+no_connect")
		)
		(pad "2" smd roundrect
			(at -1.151 -0.203)
			(size 0.6 0.2)
			(layers "F.Cu" "F.Mask" "F.Paste")
			(roundrect_rratio 0.25)
			(net 417 "unconnected-(U9-QC-Pad2)")
			(pinfunction "QC")
			(pintype "output+no_connect")
		)
		(pad "3" smd roundrect
			(at -1.151 0.2)
			(size 0.6 0.2)
			(layers "F.Cu" "F.Mask" "F.Paste")
			(roundrect_rratio 0.25)
			(net 418 "unconnected-(U9-QD-Pad3)")
			(pinfunction "QD")
			(pintype "output+no_connect")
		)
		(pad "4" smd roundrect
			(at -1.151 0.597)
			(size 0.6 0.2)
			(layers "F.Cu" "F.Mask" "F.Paste")
			(roundrect_rratio 0.25)
			(net 443 "/Debug FTDI + VNA/LED_TX0")
			(pinfunction "QE")
			(pintype "output")
		)
		(pad "5" smd roundrect
			(at -0.6 1.148 90)
			(size 0.6 0.2)
			(layers "F.Cu" "F.Mask" "F.Paste")
			(roundrect_rratio 0.25)
			(net 444 "/Debug FTDI + VNA/LED_RX0")
			(pinfunction "QF")
			(pintype "output")
		)
		(pad "6" smd roundrect
			(at -0.203 1.148 90)
			(size 0.6 0.2)
			(layers "F.Cu" "F.Mask" "F.Paste")
			(roundrect_rratio 0.25)
			(net 445 "/Debug FTDI + VNA/LED_TX1")
			(pinfunction "QG")
			(pintype "output")
		)
		(pad "7" smd roundrect
			(at 0.2 1.148 90)
			(size 0.6 0.2)
			(layers "F.Cu" "F.Mask" "F.Paste")
			(roundrect_rratio 0.25)
			(net 446 "/Debug FTDI + VNA/LED_RX1")
			(pinfunction "QH")
			(pintype "output")
		)
		(pad "8" smd roundrect
			(at 0.597 1.148 90)
			(size 0.6 0.2)
			(layers "F.Cu" "F.Mask" "F.Paste")
			(roundrect_rratio 0.25)
			(net 1 "GND")
			(pinfunction "GND")
			(pintype "power_in")
		)
		(pad "9" smd roundrect
			(at 1.148 0.597)
			(size 0.6 0.2)
			(layers "F.Cu" "F.Mask" "F.Paste")
			(roundrect_rratio 0.25)
			(net 419 "unconnected-(U9-QH'-Pad9)")
			(pinfunction "QH'")
			(pintype "output+no_connect")
		)
		(pad "10" smd roundrect
			(at 1.148 0.2)
			(size 0.6 0.2)
			(layers "F.Cu" "F.Mask" "F.Paste")
			(roundrect_rratio 0.25)
			(net 6 "/Debug FTDI + VNA/FTDI_3V3")
			(pinfunction "~{SRCLR}")
			(pintype "input")
		)
		(pad "11" smd roundrect
			(at 1.148 -0.203)
			(size 0.6 0.2)
			(layers "F.Cu" "F.Mask" "F.Paste")
			(roundrect_rratio 0.25)
			(net 794 "/Debug FTDI + VNA/FTDI_EECLK")
			(pinfunction "SRCLK")
			(pintype "input")
		)
		(pad "12" smd roundrect
			(at 1.148 -0.6)
			(size 0.6 0.2)
			(layers "F.Cu" "F.Mask" "F.Paste")
			(roundrect_rratio 0.25)
			(net 780 "/Debug FTDI + VNA/FTDI_EECS")
			(pinfunction "RCLK")
			(pintype "input")
		)
		(pad "13" smd roundrect
			(at 0.597 -1.151 90)
			(size 0.6 0.2)
			(layers "F.Cu" "F.Mask" "F.Paste")
			(roundrect_rratio 0.25)
			(net 372 "/Debug FTDI + VNA/FTDI_PWREN")
			(pinfunction "~{OE}")
			(pintype "input")
		)
		(pad "14" smd roundrect
			(at 0.2 -1.151 90)
			(size 0.6 0.2)
			(layers "F.Cu" "F.Mask" "F.Paste")
			(roundrect_rratio 0.25)
			(net 793 "/Debug FTDI + VNA/FTDI_EEDAT")
			(pinfunction "SER")
			(pintype "input")
		)
		(pad "15" smd roundrect
			(at -0.203 -1.151 90)
			(size 0.6 0.2)
			(layers "F.Cu" "F.Mask" "F.Paste")
			(roundrect_rratio 0.25)
			(net 420 "unconnected-(U9-QA-Pad15)")
			(pinfunction "QA")
			(pintype "output+no_connect")
		)
		(pad "16" smd roundrect
			(at -0.6 -1.151 90)
			(size 0.6 0.2)
			(layers "F.Cu" "F.Mask" "F.Paste")
			(roundrect_rratio 0.25)
			(net 6 "/Debug FTDI + VNA/FTDI_3V3")
			(pinfunction "VCC")
			(pintype "power_in")
		)
		(pad "17" smd roundrect
			(at 0 0 90)
			(size 1.2 1.2)
			(layers "F.Cu" "F.Mask" "F.Paste")
			(roundrect_rratio 0.04166666667)
			(net 421 "unconnected-(U9-EP-Pad17)")
			(pinfunction "EP")
			(pintype "no_connect")
		)
	)
	(footprint "antmicro-footprints:C_0805_2012Metric"
		(layer "F.Cu")
		(at 260.9555 155.371 90)
		(descr "Capacitor SMD 0805")
		(tags "capacitor SMD 0805")
		(property "Reference" "C178"
			(at -4.699 1.3445 90)
			(layer "F.SilkS")
			(effects
				(font
					(size 0.7 0.7)
					(thickness 0.15)
				)
				(justify left bottom)
			)
		)
		(property "Value" "C_22u_25V_0805"
			(at -2.055717 1.963152 90)
			(layer "F.Fab")
			(effects
				(font
					(size 0.7 0.7)
					(thickness 0.15)
				)
				(justify left bottom)
			)
		)
		(property "Datasheet" "https://product.samsungsem.com/mlcc/CL21A226MAYNNN.do"
			(at 0 0 90)
			(layer "F.Fab")
			(hide yes)
			(effects
				(font
					(size 1.27 1.27)
					(thickness 0.15)
				)
			)
		)
		(property "Manufacturer" "Samsung Electro-Mechanics"
			(at 0 0 90)
			(unlocked yes)
			(layer "F.Fab")
			(hide yes)
			(effects
				(font
					(size 1 1)
					(thickness 0.15)
				)
			)
		)
		(property "MPN" "CL21A226MAYNNNE"
			(at 0 0 90)
			(unlocked yes)
			(layer "F.Fab")
			(hide yes)
			(effects
				(font
					(size 1 1)
					(thickness 0.15)
				)
			)
		)
		(property "Val" "22u"
			(at 0 0 90)
			(unlocked yes)
			(layer "F.Fab")
			(hide yes)
			(effects
				(font
					(size 1 1)
					(thickness 0.15)
				)
			)
		)
		(property "License" "Apache-2.0"
			(at 0 0 90)
			(unlocked yes)
			(layer "F.Fab")
			(hide yes)
			(effects
				(font
					(size 1 1)
					(thickness 0.15)
				)
			)
		)
		(property "Author" "Antmicro"
			(at 0 0 90)
			(unlocked yes)
			(layer "F.Fab")
			(hide yes)
			(effects
				(font
					(size 1 1)
					(thickness 0.15)
				)
			)
		)
		(property "Voltage" "25V"
			(at 0 0 90)
			(unlocked yes)
			(layer "F.Fab")
			(hide yes)
			(effects
				(font
					(size 1 1)
					(thickness 0.15)
				)
			)
		)
		(property "Dielectric" "X5R"
			(at 0 0 90)
			(unlocked yes)
			(layer "F.Fab")
			(hide yes)
			(effects
				(font
					(size 1 1)
					(thickness 0.15)
				)
			)
		)
		(property "Public" "False"
			(at 0 0 90)
			(unlocked yes)
			(layer "F.Fab")
			(hide yes)
			(effects
				(font
					(size 1 1)
					(thickness 0.15)
				)
			)
		)
		(sheetname "/Supply/DC-DC IO/")
		(sheetfile "dc-dc-io.kicad_sch")
		(attr smd)
		(fp_line
			(start -0.3 -0.7)
			(end 0.3 -0.7)
			(stroke
				(width 0.15)
				(type solid)
			)
			(layer "F.SilkS")
		)
		(fp_line
			(start -0.3 0.7)
			(end 0.3 0.7)
			(stroke
				(width 0.15)
				(type solid)
			)
			(layer "F.SilkS")
		)
		(fp_rect
			(start 1.95 -0.9)
			(end -1.95 0.9)
			(stroke
				(width 0.05)
				(type default)
			)
			(fill no)
			(layer "F.CrtYd")
		)
		(fp_rect
			(start -0.95 -0.675)
			(end 0.95 0.675)
			(stroke
				(width 0.15)
				(type solid)
			)
			(fill no)
			(layer "F.Fab")
		)
		(fp_text user "${REFERENCE}"
			(at -1.9 3.947 90)
			(layer "F.Fab")
			(effects
				(font
					(size 0.7 0.7)
					(thickness 0.15)
				)
				(justify left bottom)
			)
		)
		(fp_text user "Author: Antmicro"
			(at -1.9 5.947 90)
			(layer "F.Fab")
			(effects
				(font
					(size 0.7 0.7)
					(thickness 0.15)
				)
				(justify left bottom)
			)
		)
		(fp_text user "License: Apache-2.0"
			(at -1.9 4.947 90)
			(layer "F.Fab")
			(effects
				(font
					(size 0.7 0.7)
					(thickness 0.15)
				)
				(justify left bottom)
			)
		)
		(pad "1" smd roundrect
			(at -1.1 0 90)
			(size 1.2 1.3)
			(layers "F.Cu" "F.Mask" "F.Paste")
			(roundrect_rratio 0.25)
			(net 1 "GND")
			(pintype "passive")
		)
		(pad "2" smd roundrect
			(at 1.1 0 90)
			(size 1.2 1.3)
			(layers "F.Cu" "F.Mask" "F.Paste")
			(roundrect_rratio 0.25)
			(net 35 "VDC")
			(pintype "passive")
		)
	)
)
